(kicad_pcb
	(version 20260206)
	(generator "pcbnew")
	(generator_version "10.0")
	(general
		(thickness 1.6)
		(legacy_teardrops no)
	)
	(paper "A4")
	(title_block
		(title "v2-tray-backplane — ms_tbp_v2.brd")
		(comment 1 "Open CloudServer (Microsoft) / footprints 159-164 of 164")
	)
	(layers
		(0 "F.Cu" signal "TOP")
		(4 "In1.Cu" signal "LYR2")
		(6 "In2.Cu" signal "LYR3")
		(8 "In3.Cu" signal "LYR4")
		(10 "In4.Cu" signal "LYR5")
		(12 "In5.Cu" signal "LYR6")
		(14 "In6.Cu" signal "LYR7")
		(2 "B.Cu" signal "BOTTOM")
		(9 "F.Adhes" user "F.Adhesive")
		(11 "B.Adhes" user "B.Adhesive")
		(13 "F.Paste" user "Package Geometry/Pastemask Top")
		(15 "B.Paste" user "Package Geometry/Pastemask Bottom")
		(5 "F.SilkS" user "Ref Des/Silkscreen Top")
		(7 "B.SilkS" user "Ref Des/Silkscreen Bottom")
		(1 "F.Mask" user "Board Geometry/Soldermask Top")
		(3 "B.Mask" user "Board Geometry/Soldermask Bottom")
		(17 "Dwgs.User" user "User.Drawings")
		(19 "Cmts.User" user "User.Comments")
		(21 "Eco1.User" user "User.Eco1")
		(23 "Eco2.User" user "User.Eco2")
		(25 "Edge.Cuts" user "Board Geometry/Outline")
		(27 "Margin" user)
		(31 "F.CrtYd" user "Package Geometry/Place Bound Top")
		(29 "B.CrtYd" user "Package Geometry/Place Bound Bottom")
		(35 "F.Fab" user "Ref Des/Assembly Top")
		(33 "B.Fab" user "Ref Des/Assembly Bottom")
	)
	(footprint ""
		(layer "F.Cu")
		(at -48.3616 2.8702 -90)
		(property "Reference" "C24"
			(at 0.00254 1.20396 90)
			(unlocked yes)
			(layer "F.SilkS")
			(effects
				(font
					(size 0.762 0.5334)
					(thickness 0.1016)
				)
			)
		)
		(property "Value" ""
			(at 0 0 270)
			(layer "F.Fab")
			(effects
				(font
					(size 1.27 1.27)
				)
			)
		)
		(duplicate_pad_numbers_are_jumpers no)
		(fp_line
			(start 0 -0.381)
			(end 0 0.381)
			(stroke
				(width 0.127)
				(type default)
			)
			(layer "F.SilkS")
		)
		(fp_poly
			(pts
				(xy 1.2533 0.6564) (xy -1.253299 0.6564) (xy -1.253299 -0.656399) (xy 1.2533 -0.656399)
			)
			(stroke
				(width 0)
				(type default)
			)
			(fill no)
			(layer "F.CrtYd")
		)
		(fp_line
			(start -0.762 0.381)
			(end 0.762 0.381)
			(stroke
				(width 0.1)
				(type default)
			)
			(layer "F.Fab")
		)
		(fp_line
			(start 0.762 0.381)
			(end 0.762 -0.381)
			(stroke
				(width 0.1)
				(type default)
			)
			(layer "F.Fab")
		)
		(fp_line
			(start -0.762 -0.381)
			(end -0.762 0.381)
			(stroke
				(width 0.1)
				(type default)
			)
			(layer "F.Fab")
		)
		(fp_line
			(start 0.762 -0.381)
			(end -0.762 -0.381)
			(stroke
				(width 0.1)
				(type default)
			)
			(layer "F.Fab")
		)
		(pad "1" smd rect
			(at -0.6477 0 270)
			(size 0.7112 0.8128)
			(layers "F.Cu" "F.Mask" "F.Paste")
			(net "P3V3_40G_B2_VCC_RX")
		)
		(pad "2" smd rect
			(at 0.6477 0 90)
			(size 0.7112 0.8128)
			(layers "F.Cu" "F.Mask" "F.Paste")
			(net "GND")
		)
	)
	(footprint ""
		(layer "F.Cu")
		(at -282.785401 44.869202 90)
		(property "Reference" "R13"
			(at 4.102202 -0.005499 90)
			(unlocked yes)
			(layer "F.SilkS")
			(effects
				(font
					(size 0.762 0.5334)
					(thickness 0.1016)
				)
			)
		)
		(property "Value" ""
			(at 0 0 90)
			(layer "F.Fab")
			(effects
				(font
					(size 1.27 1.27)
				)
			)
		)
		(duplicate_pad_numbers_are_jumpers no)
		(fp_line
			(start 0 -0.381)
			(end 0 0.381)
			(stroke
				(width 0.127)
				(type default)
			)
			(layer "F.SilkS")
		)
		(fp_poly
			(pts
				(xy 1.255601 0.6564) (xy -1.2556 0.6564) (xy -1.2556 -0.656399) (xy 1.255601 -0.656399)
			)
			(stroke
				(width 0)
				(type default)
			)
			(fill no)
			(layer "F.CrtYd")
		)
		(fp_line
			(start 0.800001 -0.399999)
			(end -0.800001 -0.399999)
			(stroke
				(width 0.1)
				(type default)
			)
			(layer "F.Fab")
		)
		(fp_line
			(start -0.800001 -0.399999)
			(end -0.800001 0.399999)
			(stroke
				(width 0.1)
				(type default)
			)
			(layer "F.Fab")
		)
		(fp_line
			(start 0.800001 0.399999)
			(end 0.800001 -0.399999)
			(stroke
				(width 0.1)
				(type default)
			)
			(layer "F.Fab")
		)
		(fp_line
			(start -0.800001 0.399999)
			(end 0.800001 0.399999)
			(stroke
				(width 0.1)
				(type default)
			)
			(layer "F.Fab")
		)
		(pad "1" smd rect
			(at -0.650001 0 90)
			(size 0.7112 0.8128)
			(layers "F.Cu" "F.Mask" "F.Paste")
			(net "P3V3_B1_QSFP")
		)
		(pad "2" smd rect
			(at 0.650001 0 270)
			(size 0.7112 0.8128)
			(layers "F.Cu" "F.Mask" "F.Paste")
			(net "P3V3_10G_B1_VCCR")
		)
	)
	(footprint ""
		(layer "F.Cu")
		(at -114.0714 16.8656 -90)
		(property "Reference" "R70"
			(at -2.8956 -0.0635 90)
			(unlocked yes)
			(layer "F.SilkS")
			(effects
				(font
					(size 0.762 0.5334)
					(thickness 0.1016)
				)
			)
		)
		(property "Value" ""
			(at 0 0 270)
			(layer "F.Fab")
			(effects
				(font
					(size 1.27 1.27)
				)
			)
		)
		(duplicate_pad_numbers_are_jumpers no)
		(fp_line
			(start 0 -0.381)
			(end 0 0.381)
			(stroke
				(width 0.127)
				(type default)
			)
			(layer "F.SilkS")
		)
		(fp_poly
			(pts
				(xy 1.255601 0.6564) (xy -1.255601 0.6564) (xy -1.255601 -0.656399) (xy 1.255601 -0.656399)
			)
			(stroke
				(width 0)
				(type default)
			)
			(fill no)
			(layer "F.CrtYd")
		)
		(fp_line
			(start -0.800001 0.399999)
			(end 0.800001 0.399999)
			(stroke
				(width 0.1)
				(type default)
			)
			(layer "F.Fab")
		)
		(fp_line
			(start 0.800001 0.399999)
			(end 0.800001 -0.399999)
			(stroke
				(width 0.1)
				(type default)
			)
			(layer "F.Fab")
		)
		(fp_line
			(start -0.800001 -0.399999)
			(end -0.800001 0.399999)
			(stroke
				(width 0.1)
				(type default)
			)
			(layer "F.Fab")
		)
		(fp_line
			(start 0.800001 -0.399999)
			(end -0.800001 -0.399999)
			(stroke
				(width 0.1)
				(type default)
			)
			(layer "F.Fab")
		)
		(pad "1" smd rect
			(at -0.650001 0 270)
			(size 0.7112 0.8128)
			(layers "F.Cu" "F.Mask" "F.Paste")
			(net "P3V3_B2_QSFP")
		)
		(pad "2" smd rect
			(at 0.650001 0 90)
			(size 0.7112 0.8128)
			(layers "F.Cu" "F.Mask" "F.Paste")
			(net "ETH40G_B2_LPMODE")
		)
	)
	(footprint ""
		(layer "F.Cu")
		(at -110.8456 14.6304)
		(property "Reference" "R68"
			(at 3.2766 0.0127 0)
			(unlocked yes)
			(layer "F.SilkS")
			(effects
				(font
					(size 0.762 0.5334)
					(thickness 0.1016)
				)
			)
		)
		(property "Value" ""
			(at 0 0 0)
			(layer "F.Fab")
			(effects
				(font
					(size 1.27 1.27)
				)
			)
		)
		(duplicate_pad_numbers_are_jumpers no)
		(fp_line
			(start 0 -0.381)
			(end 0 0.381)
			(stroke
				(width 0.127)
				(type default)
			)
			(layer "F.SilkS")
		)
		(fp_poly
			(pts
				(xy 1.255601 0.6564) (xy -1.255601 0.6564) (xy -1.255601 -0.656399) (xy 1.255601 -0.656399)
			)
			(stroke
				(width 0)
				(type default)
			)
			(fill no)
			(layer "F.CrtYd")
		)
		(fp_line
			(start -0.800001 -0.399999)
			(end -0.800001 0.399999)
			(stroke
				(width 0.1)
				(type default)
			)
			(layer "F.Fab")
		)
		(fp_line
			(start -0.800001 0.399999)
			(end 0.800001 0.399999)
			(stroke
				(width 0.1)
				(type default)
			)
			(layer "F.Fab")
		)
		(fp_line
			(start 0.800001 -0.399999)
			(end -0.800001 -0.399999)
			(stroke
				(width 0.1)
				(type default)
			)
			(layer "F.Fab")
		)
		(fp_line
			(start 0.800001 0.399999)
			(end 0.800001 -0.399999)
			(stroke
				(width 0.1)
				(type default)
			)
			(layer "F.Fab")
		)
		(pad "1" smd rect
			(at -0.650001 0)
			(size 0.7112 0.8128)
			(layers "F.Cu" "F.Mask" "F.Paste")
			(net "P3V3_B2_QSFP")
		)
		(pad "2" smd rect
			(at 0.650001 0 180)
			(size 0.7112 0.8128)
			(layers "F.Cu" "F.Mask" "F.Paste")
			(net "ETH40G_B2_SCL")
		)
	)
	(footprint ""
		(layer "F.Cu")
		(at -75.3618 12.3952 180)
		(property "Reference" "R54"
			(at -2.413 -0.0381 0)
			(unlocked yes)
			(layer "F.SilkS")
			(effects
				(font
					(size 0.762 0.5334)
					(thickness 0.1016)
				)
			)
		)
		(property "Value" ""
			(at 0 0 180)
			(layer "F.Fab")
			(effects
				(font
					(size 1.27 1.27)
				)
			)
		)
		(duplicate_pad_numbers_are_jumpers no)
		(fp_line
			(start 0 -0.381)
			(end 0 0.381)
			(stroke
				(width 0.127)
				(type default)
			)
			(layer "F.SilkS")
		)
		(fp_poly
			(pts
				(xy 1.255601 0.656399) (xy -1.255601 0.656399) (xy -1.255601 -0.6564) (xy 1.255601 -0.6564)
			)
			(stroke
				(width 0)
				(type default)
			)
			(fill no)
			(layer "F.CrtYd")
		)
		(fp_line
			(start 0.800001 0.399999)
			(end 0.800001 -0.399999)
			(stroke
				(width 0.1)
				(type default)
			)
			(layer "F.Fab")
		)
		(fp_line
			(start 0.800001 -0.399999)
			(end -0.800001 -0.399999)
			(stroke
				(width 0.1)
				(type default)
			)
			(layer "F.Fab")
		)
		(fp_line
			(start -0.800001 0.399999)
			(end 0.800001 0.399999)
			(stroke
				(width 0.1)
				(type default)
			)
			(layer "F.Fab")
		)
		(fp_line
			(start -0.800001 -0.399999)
			(end -0.800001 0.399999)
			(stroke
				(width 0.1)
				(type default)
			)
			(layer "F.Fab")
		)
		(pad "1" smd rect
			(at -0.650001 0 180)
			(size 0.7112 0.8128)
			(layers "F.Cu" "F.Mask" "F.Paste")
			(net "P3V3_B2_QSFP")
		)
		(pad "2" smd rect
			(at 0.650001 0)
			(size 0.7112 0.8128)
			(layers "F.Cu" "F.Mask" "F.Paste")
			(net "ETH10G_B2_SDA")
		)
	)
	(footprint ""
		(layer "F.Cu")
		(at -282.750001 32.059999 180)
		(property "Reference" "J5"
			(at 7.391659 -7.216021 0)
			(unlocked yes)
			(layer "F.SilkS")
			(effects
				(font
					(size 0.762 0.5334)
					(thickness 0.1016)
				)
			)
		)
		(property "Value" ""
			(at 0 0 180)
			(layer "F.Fab")
			(effects
				(font
					(size 1.27 1.27)
				)
			)
		)
		(duplicate_pad_numbers_are_jumpers no)
		(fp_line
			(start 5.499999 3.85)
			(end 4.500001 3.85)
			(stroke
				(width 0.127)
				(type default)
			)
			(layer "F.SilkS")
		)
		(fp_line
			(start 5.499999 1.499999)
			(end 5.499999 3.85)
			(stroke
				(width 0.127)
				(type default)
			)
			(layer "F.SilkS")
		)
		(fp_line
			(start 5.499999 -1.5)
			(end 5.499999 -3.85)
			(stroke
				(width 0.127)
				(type default)
			)
			(layer "F.SilkS")
		)
		(fp_line
			(start 5.499999 -3.85)
			(end 4 -3.85)
			(stroke
				(width 0.127)
				(type default)
			)
			(layer "F.SilkS")
		)
		(fp_line
			(start -4 3.85)
			(end -5.499999 3.85)
			(stroke
				(width 0.127)
				(type default)
			)
			(layer "F.SilkS")
		)
		(fp_line
			(start -5.499999 3.85)
			(end -5.499999 1.499999)
			(stroke
				(width 0.127)
				(type default)
			)
			(layer "F.SilkS")
		)
		(fp_line
			(start -5.499999 -1.5)
			(end -5.499999 -2.85)
			(stroke
				(width 0.127)
				(type default)
			)
			(layer "F.SilkS")
		)
		(fp_line
			(start -5.499999 -2.85)
			(end -4.500001 -3.85)
			(stroke
				(width 0.127)
				(type default)
			)
			(layer "F.SilkS")
		)
		(fp_poly
			(pts
				(xy -4.154 5.603301) (xy -4.154 4.349999) (xy -6.000001 4.349999) (xy -6.000001 -4.349999) (xy -4.553999 -4.349999)
				(xy -4.553999 -5.603301) (xy 4.154 -5.603301) (xy 4.154 -4.349999) (xy 6.000001 -4.349999) (xy 6.000001 4.349999)
				(xy 4.553999 4.349999) (xy 4.553999 5.603301)
			)
			(stroke
				(width 0)
				(type default)
			)
			(fill no)
			(layer "F.CrtYd")
		)
		(fp_line
			(start 5.499999 3.85)
			(end -5.499999 3.85)
			(stroke
				(width 0.1)
				(type default)
			)
			(layer "F.Fab")
		)
		(fp_line
			(start 5.499999 -3.85)
			(end 5.499999 3.85)
			(stroke
				(width 0.1)
				(type default)
			)
			(layer "F.Fab")
		)
		(fp_line
			(start -4.500001 -3.85)
			(end 5.499999 -3.85)
			(stroke
				(width 0.1)
				(type default)
			)
			(layer "F.Fab")
		)
		(fp_line
			(start -5.499999 3.85)
			(end -5.499999 -2.85)
			(stroke
				(width 0.1)
				(type default)
			)
			(layer "F.Fab")
		)
		(fp_line
			(start -5.499999 -2.85)
			(end -4.500001 -3.85)
			(stroke
				(width 0.1)
				(type default)
			)
			(layer "F.Fab")
		)
		(fp_text user "10"
			(at 5.057399 4.582279 0)
			(unlocked yes)
			(layer "F.SilkS")
			(effects
				(font
					(size 0.762 0.5334)
					(thickness 0.1016)
				)
			)
		)
		(fp_text user "11"
			(at 4.811019 -4.620141 0)
			(unlocked yes)
			(layer "F.SilkS")
			(effects
				(font
					(size 0.762 0.5334)
					(thickness 0.1016)
				)
			)
		)
		(fp_text user "*"
			(at -4.658101 5.741789 0)
			(unlocked yes)
			(layer "F.SilkS")
			(effects
				(font
					(size 0.381 0.381)
					(thickness 0.381)
				)
			)
		)
		(fp_text user "20"
			(at -5.211821 -4.538861 0)
			(unlocked yes)
			(layer "F.SilkS")
			(effects
				(font
					(size 0.762 0.5334)
					(thickness 0.1016)
				)
			)
		)
		(pad "" np_thru_hole circle
			(at -4.800001 0 180)
			(size 1.27 1.27)
			(drill 1.6002)
			(layers "*.Cu" "*.Mask")
		)
		(pad "" np_thru_hole circle
			(at 4.800001 0 180)
			(size 1.27 1.27)
			(drill 1.6002)
			(layers "*.Cu" "*.Mask")
		)
		(pad "1" smd oval
			(at -3.400001 4.099999 180)
			(size 0.508 2.0066)
			(layers "F.Cu" "F.Mask" "F.Paste")
			(net "GND")
		)
		(pad "2" smd oval
			(at -2.6 4.099999 180)
			(size 0.508 2.0066)
			(layers "F.Cu" "F.Mask" "F.Paste")
			(net "ETH10G_B1_TX_FAULT")
		)
		(pad "3" smd oval
			(at -1.799999 4.099999 180)
			(size 0.508 2.0066)
			(layers "F.Cu" "F.Mask" "F.Paste")
			(net "ETH10G_B1_TX_DIS")
		)
		(pad "4" smd oval
			(at -1.000001 4.099999 180)
			(size 0.508 2.0066)
			(layers "F.Cu" "F.Mask" "F.Paste")
			(net "ETH10G_B1_SDA")
		)
		(pad "5" smd oval
			(at -0.2 4.099999 180)
			(size 0.508 2.0066)
			(layers "F.Cu" "F.Mask" "F.Paste")
			(net "ETH10G_B1_SCL")
		)
		(pad "6" smd oval
			(at 0.599999 4.099999 180)
			(size 0.508 2.0066)
			(layers "F.Cu" "F.Mask" "F.Paste")
			(net "ETH10G_B1_MOD_ABS")
		)
		(pad "7" smd oval
			(at 1.4 4.099999 180)
			(size 0.508 2.0066)
			(layers "F.Cu" "F.Mask" "F.Paste")
			(net "ETH10G_B1_RS0")
		)
		(pad "8" smd oval
			(at 2.200001 4.099999 180)
			(size 0.508 2.0066)
			(layers "F.Cu" "F.Mask" "F.Paste")
			(net "ETH10G_B1_RX_LOS")
		)
		(pad "9" smd oval
			(at 2.999999 4.099999 180)
			(size 0.508 2.0066)
			(layers "F.Cu" "F.Mask" "F.Paste")
			(net "ETH10G_B1_RS1")
		)
		(pad "10" smd oval
			(at 3.8 4.099999 180)
			(size 0.508 2.0066)
			(layers "F.Cu" "F.Mask" "F.Paste")
			(net "GND")
		)
		(pad "11" smd oval
			(at 3.400001 -4.099999 180)
			(size 0.508 2.0066)
			(layers "F.Cu" "F.Mask" "F.Paste")
			(net "GND")
		)
		(pad "12" smd oval
			(at 2.6 -4.099999 180)
			(size 0.508 2.0066)
			(layers "F.Cu" "F.Mask" "F.Paste")
			(net "ETH10G_B1_RXN")
		)
		(pad "13" smd oval
			(at 1.799999 -4.099999 180)
			(size 0.508 2.0066)
			(layers "F.Cu" "F.Mask" "F.Paste")
			(net "ETH10G_B1_RXP")
		)
		(pad "14" smd oval
			(at 1.000001 -4.099999 180)
			(size 0.508 2.0066)
			(layers "F.Cu" "F.Mask" "F.Paste")
			(net "GND")
		)
		(pad "15" smd oval
			(at 0.2 -4.099999 180)
			(size 0.508 2.0066)
			(layers "F.Cu" "F.Mask" "F.Paste")
			(net "P3V3_10G_B1_VCCR")
		)
		(pad "16" smd oval
			(at -0.599999 -4.099999 180)
			(size 0.508 2.0066)
			(layers "F.Cu" "F.Mask" "F.Paste")
			(net "P3V3_10G_B1_VCCT")
		)
		(pad "17" smd oval
			(at -1.4 -4.099999 180)
			(size 0.508 2.0066)
			(layers "F.Cu" "F.Mask" "F.Paste")
			(net "GND")
		)
		(pad "18" smd oval
			(at -2.200001 -4.099999 180)
			(size 0.508 2.0066)
			(layers "F.Cu" "F.Mask" "F.Paste")
			(net "ETH10G_B1_TXP")
		)
		(pad "19" smd oval
			(at -2.999999 -4.099999 180)
			(size 0.508 2.0066)
			(layers "F.Cu" "F.Mask" "F.Paste")
			(net "ETH10G_B1_TXN")
		)
		(pad "20" smd oval
			(at -3.8 -4.099999 180)
			(size 0.508 2.0066)
			(layers "F.Cu" "F.Mask" "F.Paste")
			(net "GND")
		)
		(zone
			(layers "F.Cu" "B.Cu" "In1.Cu" "In2.Cu" "In3.Cu" "In4.Cu" "In5.Cu" "In6.Cu")
			(hatch none 0.5)
			(connect_pads
				(clearance 0)
			)
			(min_thickness 0.25)
			(keepout
				(tracks not_allowed)
				(vias allowed)
				(pads allowed)
				(copperpour not_allowed)
				(footprints allowed)
			)
			(placement
				(enabled no)
				(sheetname "")
			)
			(fill
				(thermal_gap 0.5)
				(thermal_bridge_width 0.5)
				(island_removal_mode 0)
			)
			(polygon
				(pts
					(arc
						(start -288.730002 32.059999)
						(mid -286.37 32.059999)
						(end -288.730002 32.059999)
					)
				)
			)
		)
		(zone
			(layers "F.Cu" "B.Cu" "In1.Cu" "In2.Cu" "In3.Cu" "In4.Cu" "In5.Cu" "In6.Cu")
			(hatch none 0.5)
			(connect_pads
				(clearance 0)
			)
			(min_thickness 0.25)
			(keepout
				(tracks not_allowed)
				(vias allowed)
				(pads allowed)
				(copperpour not_allowed)
				(footprints allowed)
			)
			(placement
				(enabled no)
				(sheetname "")
			)
			(fill
				(thermal_gap 0.5)
				(thermal_bridge_width 0.5)
				(island_removal_mode 0)
			)
			(polygon
				(pts
					(arc
						(start -279.130001 32.059999)
						(mid -276.769999 32.059999)
						(end -279.130001 32.059999)
					)
				)
			)
		)
	)
)
